(kicad_pcb
	(version 20260206)
	(generator "pcbnew")
	(generator_version "10.0")
	(general
		(thickness 1.6)
		(legacy_teardrops no)
	)
	(paper "A4")
	(title_block
		(title "Bryce Canyon_R.DPB_16317-1_OCP.brd")
		(comment 1 "Bryce Canyon / footprints 1682-1684 of 2099")
	)
	(layers
		(0 "F.Cu" signal "TOP")
		(4 "In1.Cu" signal "L2GND")
		(6 "In2.Cu" signal "L3")
		(8 "In3.Cu" signal "L4VCC")
		(10 "In4.Cu" signal "L5VCC")
		(12 "In5.Cu" signal "L6")
		(14 "In6.Cu" signal "L7GND")
		(2 "B.Cu" signal "BOTTOM")
		(9 "F.Adhes" user "F.Adhesive")
		(11 "B.Adhes" user "B.Adhesive")
		(13 "F.Paste" user "Package Geometry/Pastemask Top")
		(15 "B.Paste" user "Package Geometry/Pastemask Bottom")
		(5 "F.SilkS" user "Ref Des/Silkscreen Top")
		(7 "B.SilkS" user "Ref Des/Silkscreen Bottom")
		(1 "F.Mask" user "Board Geometry/Soldermask Top")
		(3 "B.Mask" user "Board Geometry/Soldermask Bottom")
		(17 "Dwgs.User" user "User.Drawings")
		(19 "Cmts.User" user "User.Comments")
		(21 "Eco1.User" user "User.Eco1")
		(23 "Eco2.User" user "User.Eco2")
		(25 "Edge.Cuts" user "Board Geometry/Outline")
		(27 "Margin" user)
		(31 "F.CrtYd" user "Package Geometry/Place Bound Top")
		(29 "B.CrtYd" user "Package Geometry/Place Bound Bottom")
		(35 "F.Fab" user "Ref Des/Assembly Top")
		(33 "B.Fab" user "Ref Des/Assembly Bottom")
	)
	(footprint ""
		(layer "F.Cu")
		(at 127.113284 -245.219474 90)
		(property "Reference" "C67"
			(at 0 0 90)
			(layer "F.SilkS")
			(hide yes)
			(effects
				(font
					(size 1.27 1.27)
				)
			)
		)
		(property "Value" "SCD01U16V1KX-GP"
			(at -2.8321 -1.7399 90)
			(unlocked yes)
			(layer "F.Fab")
			(hide yes)
			(effects
				(font
					(size 1.016 1.016)
					(thickness 0.1524)
				)
			)
		)
		(property "Device Type" "C0201H13"
			(at -2.8321 -3.2639 90)
			(unlocked yes)
			(layer "F.Fab")
			(hide yes)
			(effects
				(font
					(size 1.016 1.016)
					(thickness 0.1524)
				)
			)
		)
		(duplicate_pad_numbers_are_jumpers no)
		(fp_rect
			(start -0.2794 0.6477)
			(end 0.2794 -0.6477)
			(stroke
				(width 0)
				(type default)
			)
			(fill no)
			(layer "F.CrtYd")
		)
		(fp_rect
			(start -0.2794 0.6477)
			(end 0.2794 -0.6477)
			(stroke
				(width 0)
				(type default)
			)
			(fill no)
			(layer "F.Fab")
		)
		(pad "1" smd custom
			(at 0 -0.2794 90)
			(size 0.0762 0.0762)
			(layers "F.Cu" "F.Mask" "F.Paste")
			(net "SAS_HDD_RX_N3")
			(options
				(clearance outline)
				(anchor circle)
			)
			(primitives
				(gr_poly
					(pts
						(arc
							(start 0.1524 -0.127)
							(mid 0.137521 -0.162921)
							(end 0.1016 -0.1778)
						)
						(arc
							(start -0.1016 -0.1778)
							(mid -0.137521 -0.162921)
							(end -0.1524 -0.127)
						)
						(arc
							(start -0.1524 0.127)
							(mid -0.137521 0.162921)
							(end -0.1016 0.1778)
						)
						(arc
							(start 0.1016 0.1778)
							(mid 0.137521 0.162921)
							(end 0.1524 0.127)
						)
					)
					(width 0)
					(fill yes)
				)
			)
		)
		(pad "2" smd custom
			(at 0 0.2794 90)
			(size 0.0762 0.0762)
			(layers "F.Cu" "F.Mask" "F.Paste")
			(net "PHY_SCC_B_TO_DRV_B_3_DN")
			(options
				(clearance outline)
				(anchor circle)
			)
			(primitives
				(gr_poly
					(pts
						(arc
							(start 0.1524 -0.127)
							(mid 0.137521 -0.162921)
							(end 0.1016 -0.1778)
						)
						(arc
							(start -0.1016 -0.1778)
							(mid -0.137521 -0.162921)
							(end -0.1524 -0.127)
						)
						(arc
							(start -0.1524 0.127)
							(mid -0.137521 0.162921)
							(end -0.1016 0.1778)
						)
						(arc
							(start 0.1016 0.1778)
							(mid 0.137521 0.162921)
							(end 0.1524 0.127)
						)
					)
					(width 0)
					(fill yes)
				)
			)
		)
	)
	(footprint ""
		(layer "F.Cu")
		(at 51.7398 -99.7204 180)
		(property "Reference" "Q232"
			(at 0 0 180)
			(layer "F.SilkS")
			(hide yes)
			(effects
				(font
					(size 1.27 1.27)
				)
			)
		)
		(property "Value" "2N7002K-2-GP"
			(at 0.127 -8.9662 180)
			(unlocked yes)
			(layer "F.Fab")
			(hide yes)
			(effects
				(font
					(size 1.016 1.016)
					(thickness 0.1524)
				)
			)
		)
		(property "Device Type" "SOT23DGS2D4H44"
			(at 0.127 -10.4902 180)
			(unlocked yes)
			(layer "F.Fab")
			(hide yes)
			(effects
				(font
					(size 1.016 1.016)
					(thickness 0.1524)
				)
			)
		)
		(duplicate_pad_numbers_are_jumpers no)
		(fp_line
			(start 1.651 1.778)
			(end 1.651 -1.778)
			(stroke
				(width 0.1524)
				(type default)
			)
			(layer "F.SilkS")
		)
		(fp_line
			(start 1.651 -1.778)
			(end -1.651 -1.778)
			(stroke
				(width 0.1524)
				(type default)
			)
			(layer "F.SilkS")
		)
		(fp_line
			(start -1.651 1.778)
			(end 1.651 1.778)
			(stroke
				(width 0.1524)
				(type default)
			)
			(layer "F.SilkS")
		)
		(fp_line
			(start -1.651 -1.778)
			(end -1.651 1.778)
			(stroke
				(width 0.1524)
				(type default)
			)
			(layer "F.SilkS")
		)
		(fp_poly
			(pts
				(xy -1.778 1.8796) (xy -1.778 -1.8796) (xy 1.778 -1.8796) (xy 1.778 1.8796)
			)
			(stroke
				(width 0)
				(type default)
			)
			(fill no)
			(layer "F.CrtYd")
		)
		(fp_poly
			(pts
				(xy -1.778 1.8796) (xy -1.778 -1.8796) (xy 1.778 -1.8796) (xy 1.778 1.8796)
			)
			(stroke
				(width 0)
				(type default)
			)
			(fill no)
			(layer "F.Fab")
		)
		(pad "D" smd custom
			(at 0 -0.9525 180)
			(size 0.1905 0.1905)
			(layers "F.Cu" "F.Mask" "F.Paste")
			(net "FLT_HDD13_N")
			(options
				(clearance outline)
				(anchor circle)
			)
			(primitives
				(gr_poly
					(pts
						(arc
							(start -0.1778 0.5715)
							(mid -0.321484 0.511984)
							(end -0.381 0.3683)
						)
						(arc
							(start -0.381 -0.3683)
							(mid -0.321484 -0.511984)
							(end -0.1778 -0.5715)
						)
						(arc
							(start 0.1778 -0.5715)
							(mid 0.321484 -0.511984)
							(end 0.381 -0.3683)
						)
						(arc
							(start 0.381 0.3683)
							(mid 0.321484 0.511984)
							(end 0.1778 0.5715)
						)
					)
					(width 0)
					(fill yes)
				)
			)
		)
		(pad "G" smd custom
			(at -0.98425 0.9525 180)
			(size 0.1905 0.1905)
			(layers "F.Cu" "F.Mask" "F.Paste")
			(net "DRIVE_B_13_FLT_LED")
			(options
				(clearance outline)
				(anchor circle)
			)
			(primitives
				(gr_poly
					(pts
						(arc
							(start -0.1778 0.5715)
							(mid -0.321484 0.511984)
							(end -0.381 0.3683)
						)
						(arc
							(start -0.381 -0.3683)
							(mid -0.321484 -0.511984)
							(end -0.1778 -0.5715)
						)
						(arc
							(start 0.1778 -0.5715)
							(mid 0.321484 -0.511984)
							(end 0.381 -0.3683)
						)
						(arc
							(start 0.381 0.3683)
							(mid 0.321484 0.511984)
							(end 0.1778 0.5715)
						)
					)
					(width 0)
					(fill yes)
				)
			)
		)
		(pad "S" smd custom
			(at 0.98425 0.9525 180)
			(size 0.1905 0.1905)
			(layers "F.Cu" "F.Mask" "F.Paste")
			(net "GND")
			(options
				(clearance outline)
				(anchor circle)
			)
			(primitives
				(gr_poly
					(pts
						(arc
							(start -0.1778 0.5715)
							(mid -0.321484 0.511984)
							(end -0.381 0.3683)
						)
						(arc
							(start -0.381 -0.3683)
							(mid -0.321484 -0.511984)
							(end -0.1778 -0.5715)
						)
						(arc
							(start 0.1778 -0.5715)
							(mid 0.321484 -0.511984)
							(end 0.381 -0.3683)
						)
						(arc
							(start 0.381 0.3683)
							(mid 0.321484 0.511984)
							(end 0.1778 0.5715)
						)
					)
					(width 0)
					(fill yes)
				)
			)
		)
	)
	(footprint ""
		(layer "F.Cu")
		(at 190.213488 -130.21945 90)
		(property "Reference" "C249"
			(at 0 0 90)
			(layer "F.SilkS")
			(hide yes)
			(effects
				(font
					(size 1.27 1.27)
				)
			)
		)
		(property "Value" "SCD01U16V1KX-GP"
			(at -2.8321 -1.7399 90)
			(unlocked yes)
			(layer "F.Fab")
			(hide yes)
			(effects
				(font
					(size 1.016 1.016)
					(thickness 0.1524)
				)
			)
		)
		(property "Device Type" "C0201H13"
			(at -2.8321 -3.2639 90)
			(unlocked yes)
			(layer "F.Fab")
			(hide yes)
			(effects
				(font
					(size 1.016 1.016)
					(thickness 0.1524)
				)
			)
		)
		(duplicate_pad_numbers_are_jumpers no)
		(fp_rect
			(start -0.2794 0.6477)
			(end 0.2794 -0.6477)
			(stroke
				(width 0)
				(type default)
			)
			(fill no)
			(layer "F.CrtYd")
		)
		(fp_rect
			(start -0.2794 0.6477)
			(end 0.2794 -0.6477)
			(stroke
				(width 0)
				(type default)
			)
			(fill no)
			(layer "F.Fab")
		)
		(pad "1" smd custom
			(at 0 -0.2794 90)
			(size 0.0762 0.0762)
			(layers "F.Cu" "F.Mask" "F.Paste")
			(net "SAS_HDD_RX_N17")
			(options
				(clearance outline)
				(anchor circle)
			)
			(primitives
				(gr_poly
					(pts
						(arc
							(start 0.1524 -0.127)
							(mid 0.137521 -0.162921)
							(end 0.1016 -0.1778)
						)
						(arc
							(start -0.1016 -0.1778)
							(mid -0.137521 -0.162921)
							(end -0.1524 -0.127)
						)
						(arc
							(start -0.1524 0.127)
							(mid -0.137521 0.162921)
							(end -0.1016 0.1778)
						)
						(arc
							(start 0.1016 0.1778)
							(mid 0.137521 0.162921)
							(end 0.1524 0.127)
						)
					)
					(width 0)
					(fill yes)
				)
			)
		)
		(pad "2" smd custom
			(at 0 0.2794 90)
			(size 0.0762 0.0762)
			(layers "F.Cu" "F.Mask" "F.Paste")
			(net "PHY_SCC_B_TO_DRV_B_17_DN")
			(options
				(clearance outline)
				(anchor circle)
			)
			(primitives
				(gr_poly
					(pts
						(arc
							(start 0.1524 -0.127)
							(mid 0.137521 -0.162921)
							(end 0.1016 -0.1778)
						)
						(arc
							(start -0.1016 -0.1778)
							(mid -0.137521 -0.162921)
							(end -0.1524 -0.127)
						)
						(arc
							(start -0.1524 0.127)
							(mid -0.137521 0.162921)
							(end -0.1016 0.1778)
						)
						(arc
							(start 0.1016 0.1778)
							(mid 0.137521 0.162921)
							(end 0.1524 0.127)
						)
					)
					(width 0)
					(fill yes)
				)
			)
		)
	)
)
